# T6G (Grand Teton) — schematic netlist excerpt (pin names and nets, part order shuffled) for the footprints in the layout excerpt that follows; sources: Cadence DE-HDL packaged netlist, KiCad conversion of 04192023_DAF0TMB3IC0_F0TG_MB_C_brd_V02_OCP.brd

PR2520  Q_RES  1 1% CHIP  pkg 0402LF  page 266 : A = P12V_HSC_SENSE2_P ; B = P12V_HSC_SENSE2_R1_P
PC97  Q_CAPP  220UF 4V 20% SPCAP  pkg SMLF  page 201 : A = PVDDCR_CPU1_P0 ; B = GND

(kicad_pcb
	(version 20260206)
	(generator "pcbnew")
	(generator_version "10.0")
	(general
		(thickness 1.6)
		(legacy_teardrops no)
	)
	(paper "A4")
	(title_block
		(title "04192023_DAF0TMB3IC0_F0TG_MB_C_brd_V02_OCP.brd")
		(comment 1 "Grand Teton / footprints 7671-7672 of 8354")
	)
	(layers
		(0 "F.Cu" signal "TOP")
		(4 "In1.Cu" signal "GND")
		(6 "In2.Cu" signal "IN1")
		(8 "In3.Cu" signal "GND1")
		(10 "In4.Cu" signal "IN2")
		(12 "In5.Cu" signal "GND2")
		(14 "In6.Cu" signal "IN3")
		(16 "In7.Cu" signal "GND3")
		(18 "In8.Cu" signal "VCC")
		(20 "In9.Cu" signal "VCC1")
		(22 "In10.Cu" signal "GND4")
		(24 "In11.Cu" signal "IN4")
		(26 "In12.Cu" signal "GND5")
		(28 "In13.Cu" signal "IN5")
		(30 "In14.Cu" signal "GND6")
		(32 "In15.Cu" signal "IN6")
		(34 "In16.Cu" signal "GND7")
		(2 "B.Cu" signal "BOTTOM")
		(9 "F.Adhes" user "F.Adhesive")
		(11 "B.Adhes" user "B.Adhesive")
		(13 "F.Paste" user "Package Geometry/Pastemask Top")
		(15 "B.Paste" user "Package Geometry/Pastemask Bottom")
		(5 "F.SilkS" user "Ref Des/Silkscreen Top")
		(7 "B.SilkS" user "Ref Des/Silkscreen Bottom")
		(1 "F.Mask" user "Board Geometry/Soldermask Top")
		(3 "B.Mask" user "Board Geometry/Soldermask Bottom")
		(17 "Dwgs.User" user "User.Drawings")
		(19 "Cmts.User" user "User.Comments")
		(21 "Eco1.User" user "User.Eco1")
		(23 "Eco2.User" user "User.Eco2")
		(25 "Edge.Cuts" user "Board Geometry/Outline")
		(27 "Margin" user)
		(31 "F.CrtYd" user "Package Geometry/Place Bound Top")
		(29 "B.CrtYd" user "Package Geometry/Place Bound Bottom")
		(35 "F.Fab" user "Ref Des/Assembly Top")
		(33 "B.Fab" user "Ref Des/Assembly Bottom")
	)
	(footprint ""
		(layer "B.Cu")
		(at 318.43726 -328.240644 -90)
		(property "Reference" "PC97"
			(at 9.490456 -0.314706 270)
			(unlocked yes)
			(layer "B.SilkS")
			(effects
				(font
					(size 0.7874 0.5842)
					(thickness 0.1524)
				)
				(justify left mirror)
			)
		)
		(property "Value" ""
			(at 0 0 90)
			(layer "B.Fab")
			(effects
				(font
					(size 1.27 1.27)
				)
				(justify mirror)
			)
		)
		(duplicate_pad_numbers_are_jumpers no)
		(fp_line
			(start -4.533392 2.249932)
			(end 4.533392 2.249932)
			(stroke
				(width 0.1524)
				(type default)
			)
			(layer "B.SilkS")
		)
		(fp_line
			(start 4.533392 2.249932)
			(end 4.533392 -2.249932)
			(stroke
				(width 0.1524)
				(type default)
			)
			(layer "B.SilkS")
		)
		(fp_line
			(start -4.533392 -2.249932)
			(end -4.533392 2.249932)
			(stroke
				(width 0.1524)
				(type default)
			)
			(layer "B.SilkS")
		)
		(fp_line
			(start 4.533392 -2.249932)
			(end -4.533392 -2.249932)
			(stroke
				(width 0.1524)
				(type default)
			)
			(layer "B.SilkS")
		)
		(fp_rect
			(start 5.39242 2.326132)
			(end 4.533392 -2.326132)
			(stroke
				(width 0)
				(type default)
			)
			(fill yes)
			(layer "B.SilkS")
		)
		(fp_line
			(start -3.750056 2.249932)
			(end 3.750056 2.249932)
			(stroke
				(width 0.1)
				(type default)
			)
			(layer "B.Fab")
		)
		(fp_line
			(start 3.750056 2.249932)
			(end 3.750056 -2.249932)
			(stroke
				(width 0.1)
				(type default)
			)
			(layer "B.Fab")
		)
		(fp_line
			(start -3.750056 -2.249932)
			(end -3.750056 2.249932)
			(stroke
				(width 0.1)
				(type default)
			)
			(layer "B.Fab")
		)
		(fp_line
			(start 3.750056 -2.249932)
			(end -3.750056 -2.249932)
			(stroke
				(width 0.1)
				(type default)
			)
			(layer "B.Fab")
		)
		(fp_text user "-"
			(at -4.77012 2.405634 270)
			(unlocked yes)
			(layer "B.SilkS")
			(effects
				(font
					(size 1.905 1.4224)
					(thickness 0.1524)
				)
				(justify left mirror)
			)
		)
		(fp_text user "+"
			(at 6.322314 0.786384 180)
			(unlocked yes)
			(layer "B.SilkS")
			(effects
				(font
					(size 1.905 1.4224)
					(thickness 0.1524)
				)
				(justify left mirror)
			)
		)
		(fp_text user "+"
			(at 6.322314 0.786384 180)
			(unlocked yes)
			(layer "B.Fab")
			(effects
				(font
					(size 1.905 1.4224)
					(thickness 0.1524)
				)
				(justify left mirror)
			)
		)
		(fp_text user "-"
			(at -4.8514 -0.14605 270)
			(unlocked yes)
			(layer "B.Fab")
			(effects
				(font
					(size 1.905 1.4224)
					(thickness 0.1524)
				)
				(justify left mirror)
			)
		)
		(pad "1" smd rect
			(at 3.199892 0 90)
			(size 2.413 2.8194)
			(layers "B.Cu" "B.Mask" "B.Paste")
			(net "PVDDCR_CPU1_P0")
		)
		(pad "2" smd rect
			(at -3.199892 0 90)
			(size 2.413 2.8194)
			(layers "B.Cu" "B.Mask" "B.Paste")
			(net "GND")
		)
	)
	(footprint ""
		(layer "B.Cu")
		(at 206.429356 -377.666504 180)
		(property "Reference" "PR2520"
			(at 0 0 0)
			(layer "B.SilkS")
			(hide yes)
			(effects
				(font
					(size 1.27 1.27)
				)
				(justify mirror)
			)
		)
		(property "Value" ""
			(at 0 0 0)
			(layer "B.Fab")
			(effects
				(font
					(size 1.27 1.27)
				)
				(justify mirror)
			)
		)
		(duplicate_pad_numbers_are_jumpers no)
		(fp_line
			(start 0.7874 0.4064)
			(end 0.7874 -0.4064)
			(stroke
				(width 0.1524)
				(type default)
			)
			(layer "B.SilkS")
		)
		(fp_line
			(start 0.7874 -0.4064)
			(end -0.7874 -0.4064)
			(stroke
				(width 0.1524)
				(type default)
			)
			(layer "B.SilkS")
		)
		(fp_line
			(start -0.7874 0.4064)
			(end 0.7874 0.4064)
			(stroke
				(width 0.1524)
				(type default)
			)
			(layer "B.SilkS")
		)
		(fp_line
			(start -0.7874 -0.4064)
			(end -0.7874 0.4064)
			(stroke
				(width 0.1524)
				(type default)
			)
			(layer "B.SilkS")
		)
		(fp_line
			(start 0.67945 0.3048)
			(end 0.67945 -0.305054)
			(stroke
				(width 0.1)
				(type default)
			)
			(layer "B.Fab")
		)
		(fp_line
			(start 0.67945 -0.305054)
			(end 0.12065 -0.305054)
			(stroke
				(width 0.1)
				(type default)
			)
			(layer "B.Fab")
		)
		(fp_line
			(start 0.12065 0.3048)
			(end 0.67945 0.3048)
			(stroke
				(width 0.1)
				(type default)
			)
			(layer "B.Fab")
		)
		(fp_line
			(start 0.12065 0.2794)
			(end 0.12065 0.3048)
			(stroke
				(width 0.1)
				(type default)
			)
			(layer "B.Fab")
		)
		(fp_line
			(start 0.12065 -0.2794)
			(end -0.12065 -0.2794)
			(stroke
				(width 0.1)
				(type default)
			)
			(layer "B.Fab")
		)
		(fp_line
			(start 0.12065 -0.305054)
			(end 0.12065 -0.2794)
			(stroke
				(width 0.1)
				(type default)
			)
			(layer "B.Fab")
		)
		(fp_line
			(start -0.120396 0.3048)
			(end -0.120396 0.2794)
			(stroke
				(width 0.1)
				(type default)
			)
			(layer "B.Fab")
		)
		(fp_line
			(start -0.120396 0.2794)
			(end 0.12065 0.2794)
			(stroke
				(width 0.1)
				(type default)
			)
			(layer "B.Fab")
		)
		(fp_line
			(start -0.12065 -0.2794)
			(end -0.12065 -0.3048)
			(stroke
				(width 0.1)
				(type default)
			)
			(layer "B.Fab")
		)
		(fp_line
			(start -0.12065 -0.3048)
			(end -0.67945 -0.3048)
			(stroke
				(width 0.1)
				(type default)
			)
			(layer "B.Fab")
		)
		(fp_line
			(start -0.67945 0.3048)
			(end -0.120396 0.3048)
			(stroke
				(width 0.1)
				(type default)
			)
			(layer "B.Fab")
		)
		(fp_line
			(start -0.67945 -0.3048)
			(end -0.67945 0.3048)
			(stroke
				(width 0.1)
				(type default)
			)
			(layer "B.Fab")
		)
		(pad "1" smd circle
			(at 0.40005 0)
			(size 0 0)
			(layers "B.Cu" "B.Mask" "B.Paste")
			(net "P12V_HSC_SENSE2_P")
		)
		(pad "2" smd circle
			(at -0.40005 0)
			(size 0 0)
			(layers "B.Cu" "B.Mask" "B.Paste")
			(net "P12V_HSC_SENSE2_R1_P")
		)
	)
)
